(kicad_pcb
	(version 20260206)
	(generator "pcbnew")
	(generator_version "10.0")
	(general
		(thickness 1.6)
		(legacy_teardrops no)
	)
	(paper "A4")
	(title_block
		(title "baseboard — 13948-1b.1110WZS1818.brd")
		(comment 1 "Honey Badger (Wiwynn) / footprints 1535-1541 of 2523")
	)
	(layers
		(0 "F.Cu" signal "TOP")
		(4 "In1.Cu" signal "L2GND")
		(6 "In2.Cu" signal "L3")
		(8 "In3.Cu" signal "L4VCC")
		(10 "In4.Cu" signal "L5VCC")
		(12 "In5.Cu" signal "L6")
		(14 "In6.Cu" signal "L7GND")
		(2 "B.Cu" signal "BOTTOM")
		(9 "F.Adhes" user "F.Adhesive")
		(11 "B.Adhes" user "B.Adhesive")
		(13 "F.Paste" user "Package Geometry/Pastemask Top")
		(15 "B.Paste" user "Package Geometry/Pastemask Bottom")
		(5 "F.SilkS" user "Ref Des/Silkscreen Top")
		(7 "B.SilkS" user "Ref Des/Silkscreen Bottom")
		(1 "F.Mask" user "Board Geometry/Soldermask Top")
		(3 "B.Mask" user "Board Geometry/Soldermask Bottom")
		(17 "Dwgs.User" user "User.Drawings")
		(19 "Cmts.User" user "User.Comments")
		(21 "Eco1.User" user "User.Eco1")
		(23 "Eco2.User" user "User.Eco2")
		(25 "Edge.Cuts" user "Board Geometry/Outline")
		(27 "Margin" user)
		(31 "F.CrtYd" user "Package Geometry/Place Bound Top")
		(29 "B.CrtYd" user "Package Geometry/Place Bound Bottom")
		(35 "F.Fab" user "Ref Des/Assembly Top")
		(33 "B.Fab" user "Ref Des/Assembly Bottom")
	)
	(footprint ""
		(layer "F.Cu")
		(at 41.402 -171.958)
		(property "Reference" "SQ15"
			(at 0 0 0)
			(layer "F.SilkS")
			(hide yes)
			(effects
				(font
					(size 1.27 1.27)
				)
			)
		)
		(property "Value" "2N7002A-7-GP"
			(at 0.127 -8.9662 0)
			(unlocked yes)
			(layer "F.Fab")
			(hide yes)
			(effects
				(font
					(size 1.016 1.016)
					(thickness 0.1524)
				)
			)
		)
		(property "Device Type" "SOT23DGS2D4H48"
			(at 0.127 -10.4902 0)
			(unlocked yes)
			(layer "F.Fab")
			(hide yes)
			(effects
				(font
					(size 1.016 1.016)
					(thickness 0.1524)
				)
			)
		)
		(duplicate_pad_numbers_are_jumpers no)
		(fp_line
			(start -1.651 -1.778)
			(end -1.651 1.778)
			(stroke
				(width 0.1524)
				(type default)
			)
			(layer "F.SilkS")
		)
		(fp_line
			(start -1.651 1.778)
			(end 1.651 1.778)
			(stroke
				(width 0.1524)
				(type default)
			)
			(layer "F.SilkS")
		)
		(fp_line
			(start 1.651 -1.778)
			(end -1.651 -1.778)
			(stroke
				(width 0.1524)
				(type default)
			)
			(layer "F.SilkS")
		)
		(fp_line
			(start 1.651 1.778)
			(end 1.651 -1.778)
			(stroke
				(width 0.1524)
				(type default)
			)
			(layer "F.SilkS")
		)
		(fp_poly
			(pts
				(xy -1.778 1.8796) (xy -1.778 -1.8796) (xy 1.778 -1.8796) (xy 1.778 1.8796)
			)
			(stroke
				(width 0)
				(type default)
			)
			(fill no)
			(layer "F.CrtYd")
		)
		(fp_poly
			(pts
				(xy -1.778 1.8796) (xy -1.778 -1.8796) (xy 1.778 -1.8796) (xy 1.778 1.8796)
			)
			(stroke
				(width 0)
				(type default)
			)
			(fill no)
			(layer "F.Fab")
		)
		(pad "D" smd custom
			(at 0 -0.9525)
			(size 0.1905 0.1905)
			(layers "F.Cu" "F.Mask" "F.Paste")
			(net "P3V3_STBY_R7")
			(options
				(clearance outline)
				(anchor circle)
			)
			(primitives
				(gr_poly
					(pts
						(arc
							(start -0.1778 0.5715)
							(mid -0.321484 0.511984)
							(end -0.381 0.3683)
						)
						(arc
							(start -0.381 -0.3683)
							(mid -0.321484 -0.511984)
							(end -0.1778 -0.5715)
						)
						(arc
							(start 0.1778 -0.5715)
							(mid 0.321484 -0.511984)
							(end 0.381 -0.3683)
						)
						(arc
							(start 0.381 0.3683)
							(mid 0.321484 0.511984)
							(end 0.1778 0.5715)
						)
					)
					(width 0)
					(fill yes)
				)
			)
		)
		(pad "G" smd custom
			(at -0.98425 0.9525)
			(size 0.1905 0.1905)
			(layers "F.Cu" "F.Mask" "F.Paste")
			(net "CPU_EXP_RESET_N")
			(options
				(clearance outline)
				(anchor circle)
			)
			(primitives
				(gr_poly
					(pts
						(arc
							(start -0.1778 0.5715)
							(mid -0.321484 0.511984)
							(end -0.381 0.3683)
						)
						(arc
							(start -0.381 -0.3683)
							(mid -0.321484 -0.511984)
							(end -0.1778 -0.5715)
						)
						(arc
							(start 0.1778 -0.5715)
							(mid 0.321484 -0.511984)
							(end 0.381 -0.3683)
						)
						(arc
							(start 0.381 0.3683)
							(mid 0.321484 0.511984)
							(end 0.1778 0.5715)
						)
					)
					(width 0)
					(fill yes)
				)
			)
		)
		(pad "S" smd custom
			(at 0.98425 0.9525)
			(size 0.1905 0.1905)
			(layers "F.Cu" "F.Mask" "F.Paste")
			(net "GND")
			(options
				(clearance outline)
				(anchor circle)
			)
			(primitives
				(gr_poly
					(pts
						(arc
							(start -0.1778 0.5715)
							(mid -0.321484 0.511984)
							(end -0.381 0.3683)
						)
						(arc
							(start -0.381 -0.3683)
							(mid -0.321484 -0.511984)
							(end -0.1778 -0.5715)
						)
						(arc
							(start 0.1778 -0.5715)
							(mid 0.321484 -0.511984)
							(end 0.381 -0.3683)
						)
						(arc
							(start 0.381 0.3683)
							(mid 0.321484 0.511984)
							(end 0.1778 0.5715)
						)
					)
					(width 0)
					(fill yes)
				)
			)
		)
	)
	(footprint ""
		(layer "F.Cu")
		(at 201.041 -197.231 180)
		(property "Reference" "C263"
			(at 0 0 180)
			(layer "F.SilkS")
			(hide yes)
			(effects
				(font
					(size 1.27 1.27)
				)
			)
		)
		(property "Value" "SCD1U16V2KX-3GP"
			(at 1.1811 -2.7051 180)
			(unlocked yes)
			(layer "F.Fab")
			(hide yes)
			(effects
				(font
					(size 1.016 1.016)
					(thickness 0.1524)
				)
			)
		)
		(property "Device Type" "C402H22"
			(at 1.1811 -4.2291 180)
			(unlocked yes)
			(layer "F.Fab")
			(hide yes)
			(effects
				(font
					(size 1.016 1.016)
					(thickness 0.1524)
				)
			)
		)
		(duplicate_pad_numbers_are_jumpers no)
		(fp_rect
			(start -0.4318 0.9525)
			(end 0.4318 -0.9525)
			(stroke
				(width 0)
				(type default)
			)
			(fill no)
			(layer "F.CrtYd")
		)
		(fp_rect
			(start -0.4318 0.9525)
			(end 0.4318 -0.9525)
			(stroke
				(width 0)
				(type default)
			)
			(fill no)
			(layer "F.Fab")
		)
		(pad "1" smd custom
			(at 0 -0.4445 180)
			(size 0.1524 0.1524)
			(layers "F.Cu" "F.Mask" "F.Paste")
			(net "P3V3_STBY")
			(options
				(clearance outline)
				(anchor circle)
			)
			(primitives
				(gr_poly
					(pts
						(arc
							(start 0.3048 -0.2032)
							(mid 0.275042 -0.275042)
							(end 0.2032 -0.3048)
						)
						(arc
							(start -0.2032 -0.3048)
							(mid -0.275042 -0.275042)
							(end -0.3048 -0.2032)
						)
						(arc
							(start -0.3048 0.2032)
							(mid -0.275042 0.275042)
							(end -0.2032 0.3048)
						)
						(arc
							(start 0.2032 0.3048)
							(mid 0.275042 0.275042)
							(end 0.3048 0.2032)
						)
					)
					(width 0)
					(fill yes)
				)
			)
		)
		(pad "2" smd custom
			(at 0 0.4445 180)
			(size 0.1524 0.1524)
			(layers "F.Cu" "F.Mask" "F.Paste")
			(net "GND")
			(options
				(clearance outline)
				(anchor circle)
			)
			(primitives
				(gr_poly
					(pts
						(arc
							(start 0.3048 -0.2032)
							(mid 0.275042 -0.275042)
							(end 0.2032 -0.3048)
						)
						(arc
							(start -0.2032 -0.3048)
							(mid -0.275042 -0.275042)
							(end -0.3048 -0.2032)
						)
						(arc
							(start -0.3048 0.2032)
							(mid -0.275042 0.275042)
							(end -0.2032 0.3048)
						)
						(arc
							(start 0.2032 0.3048)
							(mid 0.275042 0.275042)
							(end 0.3048 0.2032)
						)
					)
					(width 0)
					(fill yes)
				)
			)
		)
	)
	(footprint ""
		(layer "F.Cu")
		(at 240.411 -15.113 90)
		(property "Reference" "R683"
			(at 0 0 90)
			(layer "F.SilkS")
			(hide yes)
			(effects
				(font
					(size 1.27 1.27)
				)
			)
		)
		(property "Value" "0R2J-2-GP"
			(at 0.064008 -3.993896 90)
			(unlocked yes)
			(layer "F.Fab")
			(hide yes)
			(effects
				(font
					(size 1.016 1.016)
					(thickness 0.1524)
				)
			)
		)
		(property "Device Type" "R402H16"
			(at 0.064008 -5.517896 90)
			(unlocked yes)
			(layer "F.Fab")
			(hide yes)
			(effects
				(font
					(size 1.016 1.016)
					(thickness 0.1524)
				)
			)
		)
		(duplicate_pad_numbers_are_jumpers no)
		(fp_line
			(start 0.508 -0.9398)
			(end -0.508 -0.9398)
			(stroke
				(width 0.1524)
				(type default)
			)
			(layer "F.SilkS")
		)
		(fp_line
			(start -0.508 -0.9398)
			(end -0.508 0.9398)
			(stroke
				(width 0.1524)
				(type default)
			)
			(layer "F.SilkS")
		)
		(fp_rect
			(start -0.508 0.9398)
			(end 0.508 -0.9398)
			(stroke
				(width 0)
				(type default)
			)
			(fill no)
			(layer "F.CrtYd")
		)
		(fp_rect
			(start -0.508 0.9398)
			(end 0.508 -0.9398)
			(stroke
				(width 0)
				(type default)
			)
			(fill no)
			(layer "F.Fab")
		)
		(pad "1" smd custom
			(at 0 -0.4445 90)
			(size 0.1397 0.1397)
			(layers "F.Cu" "F.Mask" "F.Paste")
			(net "BMC_ENCLOSURE_LED_R")
			(options
				(clearance outline)
				(anchor circle)
			)
			(primitives
				(gr_poly
					(pts
						(arc
							(start -0.1778 -0.2794)
							(mid -0.249642 -0.249642)
							(end -0.2794 -0.1778)
						)
						(arc
							(start -0.2794 0.1778)
							(mid -0.249642 0.249642)
							(end -0.1778 0.2794)
						)
						(arc
							(start 0.1778 0.2794)
							(mid 0.249642 0.249642)
							(end 0.2794 0.1778)
						)
						(arc
							(start 0.2794 -0.1778)
							(mid 0.249642 -0.249642)
							(end 0.1778 -0.2794)
						)
					)
					(width 0)
					(fill yes)
				)
			)
		)
		(pad "2" smd custom
			(at 0 0.4445 90)
			(size 0.1397 0.1397)
			(layers "F.Cu" "F.Mask" "F.Paste")
			(net "BMC_ENCLOSURE_LED")
			(options
				(clearance outline)
				(anchor circle)
			)
			(primitives
				(gr_poly
					(pts
						(arc
							(start -0.1778 -0.2794)
							(mid -0.249642 -0.249642)
							(end -0.2794 -0.1778)
						)
						(arc
							(start -0.2794 0.1778)
							(mid -0.249642 0.249642)
							(end -0.1778 0.2794)
						)
						(arc
							(start 0.1778 0.2794)
							(mid 0.249642 0.249642)
							(end 0.2794 0.1778)
						)
						(arc
							(start 0.2794 -0.1778)
							(mid 0.249642 -0.249642)
							(end 0.1778 -0.2794)
						)
					)
					(width 0)
					(fill yes)
				)
			)
		)
	)
	(footprint ""
		(layer "F.Cu")
		(at 292.481 -157.734 180)
		(property "Reference" "R618"
			(at 0 0 180)
			(layer "F.SilkS")
			(hide yes)
			(effects
				(font
					(size 1.27 1.27)
				)
			)
		)
		(property "Value" "0R2J-2-GP"
			(at 0.064008 -3.993896 180)
			(unlocked yes)
			(layer "F.Fab")
			(hide yes)
			(effects
				(font
					(size 1.016 1.016)
					(thickness 0.1524)
				)
			)
		)
		(property "Device Type" "R402H16"
			(at 0.064008 -5.517896 180)
			(unlocked yes)
			(layer "F.Fab")
			(hide yes)
			(effects
				(font
					(size 1.016 1.016)
					(thickness 0.1524)
				)
			)
		)
		(duplicate_pad_numbers_are_jumpers no)
		(fp_line
			(start 0.508 -0.9398)
			(end -0.508 -0.9398)
			(stroke
				(width 0.1524)
				(type default)
			)
			(layer "F.SilkS")
		)
		(fp_line
			(start -0.508 -0.9398)
			(end -0.508 0.9398)
			(stroke
				(width 0.1524)
				(type default)
			)
			(layer "F.SilkS")
		)
		(fp_rect
			(start -0.508 0.9398)
			(end 0.508 -0.9398)
			(stroke
				(width 0)
				(type default)
			)
			(fill no)
			(layer "F.CrtYd")
		)
		(fp_rect
			(start -0.508 0.9398)
			(end 0.508 -0.9398)
			(stroke
				(width 0)
				(type default)
			)
			(fill no)
			(layer "F.Fab")
		)
		(pad "1" smd custom
			(at 0 -0.4445 180)
			(size 0.1397 0.1397)
			(layers "F.Cu" "F.Mask" "F.Paste")
			(net "EXP_HDD_PRE_INT_N")
			(options
				(clearance outline)
				(anchor circle)
			)
			(primitives
				(gr_poly
					(pts
						(arc
							(start -0.1778 -0.2794)
							(mid -0.249642 -0.249642)
							(end -0.2794 -0.1778)
						)
						(arc
							(start -0.2794 0.1778)
							(mid -0.249642 0.249642)
							(end -0.1778 0.2794)
						)
						(arc
							(start 0.1778 0.2794)
							(mid 0.249642 0.249642)
							(end 0.2794 0.1778)
						)
						(arc
							(start 0.2794 -0.1778)
							(mid 0.249642 -0.249642)
							(end 0.1778 -0.2794)
						)
					)
					(width 0)
					(fill yes)
				)
			)
		)
		(pad "2" smd custom
			(at 0 0.4445 180)
			(size 0.1397 0.1397)
			(layers "F.Cu" "F.Mask" "F.Paste")
			(net "HDD_PRE_IO_INT_N")
			(options
				(clearance outline)
				(anchor circle)
			)
			(primitives
				(gr_poly
					(pts
						(arc
							(start -0.1778 -0.2794)
							(mid -0.249642 -0.249642)
							(end -0.2794 -0.1778)
						)
						(arc
							(start -0.2794 0.1778)
							(mid -0.249642 0.249642)
							(end -0.1778 0.2794)
						)
						(arc
							(start 0.1778 0.2794)
							(mid 0.249642 0.249642)
							(end 0.2794 0.1778)
						)
						(arc
							(start 0.2794 -0.1778)
							(mid 0.249642 -0.249642)
							(end 0.1778 -0.2794)
						)
					)
					(width 0)
					(fill yes)
				)
			)
		)
	)
	(footprint ""
		(layer "F.Cu")
		(at 318.008 -173.736 90)
		(property "Reference" "R279"
			(at 0 0 90)
			(layer "F.SilkS")
			(hide yes)
			(effects
				(font
					(size 1.27 1.27)
				)
			)
		)
		(property "Value" "0R2J-2-GP"
			(at 0.064008 -3.993896 90)
			(unlocked yes)
			(layer "F.Fab")
			(hide yes)
			(effects
				(font
					(size 1.016 1.016)
					(thickness 0.1524)
				)
			)
		)
		(property "Device Type" "R402H16"
			(at 0.064008 -5.517896 90)
			(unlocked yes)
			(layer "F.Fab")
			(hide yes)
			(effects
				(font
					(size 1.016 1.016)
					(thickness 0.1524)
				)
			)
		)
		(duplicate_pad_numbers_are_jumpers no)
		(fp_line
			(start 0.508 -0.9398)
			(end -0.508 -0.9398)
			(stroke
				(width 0.1524)
				(type default)
			)
			(layer "F.SilkS")
		)
		(fp_line
			(start -0.508 -0.9398)
			(end -0.508 0.9398)
			(stroke
				(width 0.1524)
				(type default)
			)
			(layer "F.SilkS")
		)
		(fp_rect
			(start -0.508 0.9398)
			(end 0.508 -0.9398)
			(stroke
				(width 0)
				(type default)
			)
			(fill no)
			(layer "F.CrtYd")
		)
		(fp_rect
			(start -0.508 0.9398)
			(end 0.508 -0.9398)
			(stroke
				(width 0)
				(type default)
			)
			(fill no)
			(layer "F.Fab")
		)
		(pad "1" smd custom
			(at 0 -0.4445 90)
			(size 0.1397 0.1397)
			(layers "F.Cu" "F.Mask" "F.Paste")
			(net "BMC_RXD5_R")
			(options
				(clearance outline)
				(anchor circle)
			)
			(primitives
				(gr_poly
					(pts
						(arc
							(start -0.1778 -0.2794)
							(mid -0.249642 -0.249642)
							(end -0.2794 -0.1778)
						)
						(arc
							(start -0.2794 0.1778)
							(mid -0.249642 0.249642)
							(end -0.1778 0.2794)
						)
						(arc
							(start 0.1778 0.2794)
							(mid 0.249642 0.249642)
							(end 0.2794 0.1778)
						)
						(arc
							(start 0.2794 -0.1778)
							(mid 0.249642 -0.249642)
							(end 0.1778 -0.2794)
						)
					)
					(width 0)
					(fill yes)
				)
			)
		)
		(pad "2" smd custom
			(at 0 0.4445 90)
			(size 0.1397 0.1397)
			(layers "F.Cu" "F.Mask" "F.Paste")
			(net "BMC_RXD5")
			(options
				(clearance outline)
				(anchor circle)
			)
			(primitives
				(gr_poly
					(pts
						(arc
							(start -0.1778 -0.2794)
							(mid -0.249642 -0.249642)
							(end -0.2794 -0.1778)
						)
						(arc
							(start -0.2794 0.1778)
							(mid -0.249642 0.249642)
							(end -0.1778 0.2794)
						)
						(arc
							(start 0.1778 0.2794)
							(mid 0.249642 0.249642)
							(end 0.2794 0.1778)
						)
						(arc
							(start 0.2794 -0.1778)
							(mid 0.249642 -0.249642)
							(end 0.1778 -0.2794)
						)
					)
					(width 0)
					(fill yes)
				)
			)
		)
	)
	(footprint ""
		(layer "F.Cu")
		(at 108.585 -60.071 90)
		(property "Reference" "SR706"
			(at 0 0 90)
			(layer "F.SilkS")
			(hide yes)
			(effects
				(font
					(size 1.27 1.27)
				)
			)
		)
		(property "Value" "10KR2F-2-GP"
			(at 0.064008 -3.993896 90)
			(unlocked yes)
			(layer "F.Fab")
			(hide yes)
			(effects
				(font
					(size 1.016 1.016)
					(thickness 0.1524)
				)
			)
		)
		(property "Device Type" "R402H16"
			(at 0.064008 -5.517896 90)
			(unlocked yes)
			(layer "F.Fab")
			(hide yes)
			(effects
				(font
					(size 1.016 1.016)
					(thickness 0.1524)
				)
			)
		)
		(duplicate_pad_numbers_are_jumpers no)
		(fp_line
			(start 0.508 -0.9398)
			(end -0.508 -0.9398)
			(stroke
				(width 0.1524)
				(type default)
			)
			(layer "F.SilkS")
		)
		(fp_line
			(start -0.508 -0.9398)
			(end -0.508 0.9398)
			(stroke
				(width 0.1524)
				(type default)
			)
			(layer "F.SilkS")
		)
		(fp_rect
			(start -0.508 0.9398)
			(end 0.508 -0.9398)
			(stroke
				(width 0)
				(type default)
			)
			(fill no)
			(layer "F.CrtYd")
		)
		(fp_rect
			(start -0.508 0.9398)
			(end 0.508 -0.9398)
			(stroke
				(width 0)
				(type default)
			)
			(fill no)
			(layer "F.Fab")
		)
		(pad "1" smd custom
			(at 0 -0.4445 90)
			(size 0.1397 0.1397)
			(layers "F.Cu" "F.Mask" "F.Paste")
			(net "P1V8_C")
			(options
				(clearance outline)
				(anchor circle)
			)
			(primitives
				(gr_poly
					(pts
						(arc
							(start -0.1778 -0.2794)
							(mid -0.249642 -0.249642)
							(end -0.2794 -0.1778)
						)
						(arc
							(start -0.2794 0.1778)
							(mid -0.249642 0.249642)
							(end -0.1778 0.2794)
						)
						(arc
							(start 0.1778 0.2794)
							(mid 0.249642 0.249642)
							(end 0.2794 0.1778)
						)
						(arc
							(start 0.2794 -0.1778)
							(mid 0.249642 -0.249642)
							(end 0.1778 -0.2794)
						)
					)
					(width 0)
					(fill yes)
				)
			)
		)
		(pad "2" smd custom
			(at 0 0.4445 90)
			(size 0.1397 0.1397)
			(layers "F.Cu" "F.Mask" "F.Paste")
			(net "XM_RB")
			(options
				(clearance outline)
				(anchor circle)
			)
			(primitives
				(gr_poly
					(pts
						(arc
							(start -0.1778 -0.2794)
							(mid -0.249642 -0.249642)
							(end -0.2794 -0.1778)
						)
						(arc
							(start -0.2794 0.1778)
							(mid -0.249642 0.249642)
							(end -0.1778 0.2794)
						)
						(arc
							(start 0.1778 0.2794)
							(mid 0.249642 0.249642)
							(end 0.2794 0.1778)
						)
						(arc
							(start 0.2794 -0.1778)
							(mid 0.249642 -0.249642)
							(end 0.1778 -0.2794)
						)
					)
					(width 0)
					(fill yes)
				)
			)
		)
	)
	(footprint ""
		(layer "F.Cu")
		(at 45.466 -217.043)
		(property "Reference" "C7278"
			(at 0 0 0)
			(layer "F.SilkS")
			(hide yes)
			(effects
				(font
					(size 1.27 1.27)
				)
			)
		)
		(property "Value" "SCD1U25V3JX-GP"
			(at 0 -2.8194 0)
			(unlocked yes)
			(layer "F.Fab")
			(hide yes)
			(effects
				(font
					(size 1.016 1.016)
					(thickness 0.1524)
				)
			)
		)
		(property "Device Type" "C603H36"
			(at 0 -4.3434 0)
			(unlocked yes)
			(layer "F.Fab")
			(hide yes)
			(effects
				(font
					(size 1.016 1.016)
					(thickness 0.1524)
				)
			)
		)
		(duplicate_pad_numbers_are_jumpers no)
		(fp_line
			(start 0.508 0)
			(end -0.508 0)
			(stroke
				(width 0.2032)
				(type default)
			)
			(layer "F.SilkS")
		)
		(fp_rect
			(start -0.5842 1.3335)
			(end 0.5842 -1.3335)
			(stroke
				(width 0)
				(type default)
			)
			(fill no)
			(layer "F.CrtYd")
		)
		(fp_rect
			(start -0.5842 1.3335)
			(end 0.5842 -1.3335)
			(stroke
				(width 0)
				(type default)
			)
			(fill no)
			(layer "F.Fab")
		)
		(pad "1" smd custom
			(at 0 -0.762)
			(size 0.2159 0.2159)
			(layers "F.Cu" "F.Mask" "F.Paste")
			(net "MB0_ISET_R")
			(options
				(clearance outline)
				(anchor circle)
			)
			(primitives
				(gr_poly
					(pts
						(arc
							(start -0.3302 -0.4318)
							(mid -0.402042 -0.402042)
							(end -0.4318 -0.3302)
						)
						(arc
							(start -0.4318 0.3302)
							(mid -0.402042 0.402042)
							(end -0.3302 0.4318)
						)
						(arc
							(start 0.3302 0.4318)
							(mid 0.402042 0.402042)
							(end 0.4318 0.3302)
						)
						(arc
							(start 0.4318 -0.3302)
							(mid 0.402042 -0.402042)
							(end 0.3302 -0.4318)
						)
					)
					(width 0)
					(fill yes)
				)
			)
		)
		(pad "2" smd custom
			(at 0 0.762)
			(size 0.2159 0.2159)
			(layers "F.Cu" "F.Mask" "F.Paste")
			(net "AGND_CURRENT_MON")
			(options
				(clearance outline)
				(anchor circle)
			)
			(primitives
				(gr_poly
					(pts
						(arc
							(start -0.3302 -0.4318)
							(mid -0.402042 -0.402042)
							(end -0.4318 -0.3302)
						)
						(arc
							(start -0.4318 0.3302)
							(mid -0.402042 0.402042)
							(end -0.3302 0.4318)
						)
						(arc
							(start 0.3302 0.4318)
							(mid 0.402042 0.402042)
							(end 0.4318 0.3302)
						)
						(arc
							(start 0.4318 -0.3302)
							(mid 0.402042 -0.402042)
							(end 0.3302 -0.4318)
						)
					)
					(width 0)
					(fill yes)
				)
			)
		)
	)
)
